(kicad_pcb
	(version 20260206)
	(generator "pcbnew")
	(generator_version "10.0")
	(general
		(thickness 1.6)
		(legacy_teardrops no)
	)
	(paper "A4")
	(title_block
		(title "Bryce Canyon_IOM_IOC_16318-2_OCP.brd")
		(comment 1 "Bryce Canyon / footprints 105-110 of 1605")
	)
	(layers
		(0 "F.Cu" signal "TOP")
		(4 "In1.Cu" signal "L2GND")
		(6 "In2.Cu" signal "L3")
		(8 "In3.Cu" signal "L4VCC")
		(10 "In4.Cu" signal "L5VCC")
		(12 "In5.Cu" signal "L6")
		(14 "In6.Cu" signal "L7GND")
		(2 "B.Cu" signal "BOTTOM")
		(9 "F.Adhes" user "F.Adhesive")
		(11 "B.Adhes" user "B.Adhesive")
		(13 "F.Paste" user "Package Geometry/Pastemask Top")
		(15 "B.Paste" user "Package Geometry/Pastemask Bottom")
		(5 "F.SilkS" user "Ref Des/Silkscreen Top")
		(7 "B.SilkS" user "Ref Des/Silkscreen Bottom")
		(1 "F.Mask" user "Board Geometry/Soldermask Top")
		(3 "B.Mask" user "Board Geometry/Soldermask Bottom")
		(17 "Dwgs.User" user "User.Drawings")
		(19 "Cmts.User" user "User.Comments")
		(21 "Eco1.User" user "User.Eco1")
		(23 "Eco2.User" user "User.Eco2")
		(25 "Edge.Cuts" user "Board Geometry/Outline")
		(27 "Margin" user)
		(31 "F.CrtYd" user "Package Geometry/Place Bound Top")
		(29 "B.CrtYd" user "Package Geometry/Place Bound Bottom")
		(35 "F.Fab" user "Ref Des/Assembly Top")
		(33 "B.Fab" user "Ref Des/Assembly Bottom")
	)
	(footprint ""
		(layer "F.Cu")
		(at 209.85988 -15.5702 -90)
		(property "Reference" "Q29"
			(at 0 0 270)
			(layer "F.SilkS")
			(hide yes)
			(effects
				(font
					(size 1.27 1.27)
				)
			)
		)
		(property "Value" "2N7002K-1-GP"
			(at 0.127 -8.9662 270)
			(unlocked yes)
			(layer "F.Fab")
			(hide yes)
			(effects
				(font
					(size 1.016 1.016)
					(thickness 0.1524)
				)
			)
		)
		(property "Device Type" "SOT23DGS2D4H44"
			(at 0.127 -10.4902 270)
			(unlocked yes)
			(layer "F.Fab")
			(hide yes)
			(effects
				(font
					(size 1.016 1.016)
					(thickness 0.1524)
				)
			)
		)
		(duplicate_pad_numbers_are_jumpers no)
		(fp_line
			(start -1.651 1.778)
			(end 1.651 1.778)
			(stroke
				(width 0.1524)
				(type default)
			)
			(layer "F.SilkS")
		)
		(fp_line
			(start 1.651 1.778)
			(end 1.651 -1.778)
			(stroke
				(width 0.1524)
				(type default)
			)
			(layer "F.SilkS")
		)
		(fp_line
			(start -1.651 -1.778)
			(end -1.651 1.778)
			(stroke
				(width 0.1524)
				(type default)
			)
			(layer "F.SilkS")
		)
		(fp_line
			(start 1.651 -1.778)
			(end -1.651 -1.778)
			(stroke
				(width 0.1524)
				(type default)
			)
			(layer "F.SilkS")
		)
		(fp_poly
			(pts
				(xy -1.778 1.8796) (xy -1.778 -1.8796) (xy 1.778 -1.8796) (xy 1.778 1.8796)
			)
			(stroke
				(width 0)
				(type default)
			)
			(fill no)
			(layer "F.CrtYd")
		)
		(fp_poly
			(pts
				(xy -1.778 1.8796) (xy -1.778 -1.8796) (xy 1.778 -1.8796) (xy 1.778 1.8796)
			)
			(stroke
				(width 0)
				(type default)
			)
			(fill no)
			(layer "F.Fab")
		)
		(pad "D" smd custom
			(at 0 -0.9525 270)
			(size 0.1905 0.1905)
			(layers "F.Cu" "F.Mask" "F.Paste")
			(net "BMC_ML_PWR_BLUE_LED_L")
			(options
				(clearance outline)
				(anchor circle)
			)
			(primitives
				(gr_poly
					(pts
						(arc
							(start -0.1778 0.5715)
							(mid -0.321484 0.511984)
							(end -0.381 0.3683)
						)
						(arc
							(start -0.381 -0.3683)
							(mid -0.321484 -0.511984)
							(end -0.1778 -0.5715)
						)
						(arc
							(start 0.1778 -0.5715)
							(mid 0.321484 -0.511984)
							(end 0.381 -0.3683)
						)
						(arc
							(start 0.381 0.3683)
							(mid 0.321484 0.511984)
							(end 0.1778 0.5715)
						)
					)
					(width 0)
					(fill yes)
				)
			)
		)
		(pad "G" smd custom
			(at -0.98425 0.9525 270)
			(size 0.1905 0.1905)
			(layers "F.Cu" "F.Mask" "F.Paste")
			(net "BMC_ML_PWR_BLUE_LED_R")
			(options
				(clearance outline)
				(anchor circle)
			)
			(primitives
				(gr_poly
					(pts
						(arc
							(start -0.1778 0.5715)
							(mid -0.321484 0.511984)
							(end -0.381 0.3683)
						)
						(arc
							(start -0.381 -0.3683)
							(mid -0.321484 -0.511984)
							(end -0.1778 -0.5715)
						)
						(arc
							(start 0.1778 -0.5715)
							(mid 0.321484 -0.511984)
							(end 0.381 -0.3683)
						)
						(arc
							(start 0.381 0.3683)
							(mid 0.321484 0.511984)
							(end 0.1778 0.5715)
						)
					)
					(width 0)
					(fill yes)
				)
			)
		)
		(pad "S" smd custom
			(at 0.98425 0.9525 270)
			(size 0.1905 0.1905)
			(layers "F.Cu" "F.Mask" "F.Paste")
			(net "GND")
			(options
				(clearance outline)
				(anchor circle)
			)
			(primitives
				(gr_poly
					(pts
						(arc
							(start -0.1778 0.5715)
							(mid -0.321484 0.511984)
							(end -0.381 0.3683)
						)
						(arc
							(start -0.381 -0.3683)
							(mid -0.321484 -0.511984)
							(end -0.1778 -0.5715)
						)
						(arc
							(start 0.1778 -0.5715)
							(mid 0.321484 -0.511984)
							(end 0.381 -0.3683)
						)
						(arc
							(start 0.381 0.3683)
							(mid 0.321484 0.511984)
							(end 0.1778 0.5715)
						)
					)
					(width 0)
					(fill yes)
				)
			)
		)
	)
	(footprint ""
		(layer "F.Cu")
		(at 36.9062 -158.623)
		(property "Reference" "R714"
			(at 0 0 0)
			(layer "F.SilkS")
			(hide yes)
			(effects
				(font
					(size 1.27 1.27)
				)
			)
		)
		(property "Value" "0R2J-2-GP"
			(at 0.064008 -3.993896 0)
			(unlocked yes)
			(layer "F.Fab")
			(hide yes)
			(effects
				(font
					(size 1.016 1.016)
					(thickness 0.1524)
				)
			)
		)
		(property "Device Type" "R402H16"
			(at 0.064008 -5.517896 0)
			(unlocked yes)
			(layer "F.Fab")
			(hide yes)
			(effects
				(font
					(size 1.016 1.016)
					(thickness 0.1524)
				)
			)
		)
		(duplicate_pad_numbers_are_jumpers no)
		(fp_line
			(start -0.508 -0.9398)
			(end -0.508 0.9398)
			(stroke
				(width 0.1524)
				(type default)
			)
			(layer "F.SilkS")
		)
		(fp_line
			(start 0.508 -0.9398)
			(end -0.508 -0.9398)
			(stroke
				(width 0.1524)
				(type default)
			)
			(layer "F.SilkS")
		)
		(fp_rect
			(start -0.508 0.9398)
			(end 0.508 -0.9398)
			(stroke
				(width 0)
				(type default)
			)
			(fill no)
			(layer "F.CrtYd")
		)
		(fp_rect
			(start -0.508 0.9398)
			(end 0.508 -0.9398)
			(stroke
				(width 0)
				(type default)
			)
			(fill no)
			(layer "F.Fab")
		)
		(pad "1" smd custom
			(at 0 -0.4445)
			(size 0.1397 0.1397)
			(layers "F.Cu" "F.Mask" "F.Paste")
			(net "PWM_OUT_ZONE_D")
			(options
				(clearance outline)
				(anchor circle)
			)
			(primitives
				(gr_poly
					(pts
						(arc
							(start -0.1778 -0.2794)
							(mid -0.249642 -0.249642)
							(end -0.2794 -0.1778)
						)
						(arc
							(start -0.2794 0.1778)
							(mid -0.249642 0.249642)
							(end -0.1778 0.2794)
						)
						(arc
							(start 0.1778 0.2794)
							(mid 0.249642 0.249642)
							(end 0.2794 0.1778)
						)
						(arc
							(start 0.2794 -0.1778)
							(mid 0.249642 -0.249642)
							(end 0.1778 -0.2794)
						)
					)
					(width 0)
					(fill yes)
				)
			)
		)
		(pad "2" smd custom
			(at 0 0.4445)
			(size 0.1397 0.1397)
			(layers "F.Cu" "F.Mask" "F.Paste")
			(net "FAN_PWM1_BMC")
			(options
				(clearance outline)
				(anchor circle)
			)
			(primitives
				(gr_poly
					(pts
						(arc
							(start -0.1778 -0.2794)
							(mid -0.249642 -0.249642)
							(end -0.2794 -0.1778)
						)
						(arc
							(start -0.2794 0.1778)
							(mid -0.249642 0.249642)
							(end -0.1778 0.2794)
						)
						(arc
							(start 0.1778 0.2794)
							(mid 0.249642 0.249642)
							(end 0.2794 0.1778)
						)
						(arc
							(start 0.2794 -0.1778)
							(mid 0.249642 -0.249642)
							(end 0.1778 -0.2794)
						)
					)
					(width 0)
					(fill yes)
				)
			)
		)
	)
	(footprint ""
		(layer "F.Cu")
		(at 192.303146 -133.290564)
		(property "Reference" "C280"
			(at 0 0 0)
			(layer "F.SilkS")
			(hide yes)
			(effects
				(font
					(size 1.27 1.27)
				)
			)
		)
		(property "Value" "SC1U10V2KX-1GP"
			(at 1.1811 -2.7051 0)
			(unlocked yes)
			(layer "F.Fab")
			(hide yes)
			(effects
				(font
					(size 1.016 1.016)
					(thickness 0.1524)
				)
			)
		)
		(property "Device Type" "C402H22"
			(at 1.1811 -4.2291 0)
			(unlocked yes)
			(layer "F.Fab")
			(hide yes)
			(effects
				(font
					(size 1.016 1.016)
					(thickness 0.1524)
				)
			)
		)
		(duplicate_pad_numbers_are_jumpers no)
		(fp_rect
			(start -0.4318 0.9525)
			(end 0.4318 -0.9525)
			(stroke
				(width 0)
				(type default)
			)
			(fill no)
			(layer "F.CrtYd")
		)
		(fp_rect
			(start -0.4318 0.9525)
			(end 0.4318 -0.9525)
			(stroke
				(width 0)
				(type default)
			)
			(fill no)
			(layer "F.Fab")
		)
		(pad "1" smd custom
			(at 0 -0.4445)
			(size 0.1524 0.1524)
			(layers "F.Cu" "F.Mask" "F.Paste")
			(net "GND")
			(options
				(clearance outline)
				(anchor circle)
			)
			(primitives
				(gr_poly
					(pts
						(arc
							(start 0.3048 -0.2032)
							(mid 0.275042 -0.275042)
							(end 0.2032 -0.3048)
						)
						(arc
							(start -0.2032 -0.3048)
							(mid -0.275042 -0.275042)
							(end -0.3048 -0.2032)
						)
						(arc
							(start -0.3048 0.2032)
							(mid -0.275042 0.275042)
							(end -0.2032 0.3048)
						)
						(arc
							(start 0.2032 0.3048)
							(mid 0.275042 0.275042)
							(end 0.3048 0.2032)
						)
					)
					(width 0)
					(fill yes)
				)
			)
		)
		(pad "2" smd custom
			(at 0 0.4445)
			(size 0.1524 0.1524)
			(layers "F.Cu" "F.Mask" "F.Paste")
			(net "VT235_EN")
			(options
				(clearance outline)
				(anchor circle)
			)
			(primitives
				(gr_poly
					(pts
						(arc
							(start 0.3048 -0.2032)
							(mid 0.275042 -0.275042)
							(end 0.2032 -0.3048)
						)
						(arc
							(start -0.2032 -0.3048)
							(mid -0.275042 -0.275042)
							(end -0.3048 -0.2032)
						)
						(arc
							(start -0.3048 0.2032)
							(mid -0.275042 0.275042)
							(end -0.2032 0.3048)
						)
						(arc
							(start 0.2032 0.3048)
							(mid 0.275042 0.275042)
							(end 0.3048 0.2032)
						)
					)
					(width 0)
					(fill yes)
				)
			)
		)
	)
	(footprint ""
		(layer "F.Cu")
		(at 25.844246 -186.56681 180)
		(property "Reference" "C170"
			(at 0 0 180)
			(layer "F.SilkS")
			(hide yes)
			(effects
				(font
					(size 1.27 1.27)
				)
			)
		)
		(property "Value" "SC10U16V5KX-7-GP-U"
			(at -0.0762 -6.1214 180)
			(unlocked yes)
			(layer "F.Fab")
			(hide yes)
			(effects
				(font
					(size 1.016 1.016)
					(thickness 0.1524)
				)
			)
		)
		(property "Device Type" "C805H58"
			(at -0.0762 -8.1534 180)
			(unlocked yes)
			(layer "F.Fab")
			(hide yes)
			(effects
				(font
					(size 1.016 1.016)
					(thickness 0.1524)
				)
			)
		)
		(duplicate_pad_numbers_are_jumpers no)
		(fp_line
			(start 0.635 0)
			(end -0.635 0)
			(stroke
				(width 0.508)
				(type default)
			)
			(layer "F.SilkS")
		)
		(fp_rect
			(start -0.9652 1.778)
			(end 0.9652 -1.778)
			(stroke
				(width 0)
				(type default)
			)
			(fill no)
			(layer "F.CrtYd")
		)
		(fp_poly
			(pts
				(xy -0.9652 -1.778) (xy 0.9652 -1.778) (xy 0.9652 1.778) (xy -0.9652 1.778)
			)
			(stroke
				(width 0)
				(type default)
			)
			(fill no)
			(layer "F.Fab")
		)
		(pad "1" smd rect
			(at 0 -0.9652 180)
			(size 1.397 1.143)
			(layers "F.Cu" "F.Mask" "F.Paste")
			(net "P12V_STBY_VIN_PU2")
		)
		(pad "2" smd rect
			(at 0 0.9652 180)
			(size 1.397 1.143)
			(layers "F.Cu" "F.Mask" "F.Paste")
			(net "GND")
		)
	)
	(footprint ""
		(layer "F.Cu")
		(at 28.346146 -178.17211 -90)
		(property "Reference" "R492"
			(at 0 0 270)
			(layer "F.SilkS")
			(hide yes)
			(effects
				(font
					(size 1.27 1.27)
				)
			)
		)
		(property "Value" "475KR2F-GP"
			(at 0.064008 -3.993896 270)
			(unlocked yes)
			(layer "F.Fab")
			(hide yes)
			(effects
				(font
					(size 1.016 1.016)
					(thickness 0.1524)
				)
			)
		)
		(property "Device Type" "R402H16"
			(at 0.064008 -5.517896 270)
			(unlocked yes)
			(layer "F.Fab")
			(hide yes)
			(effects
				(font
					(size 1.016 1.016)
					(thickness 0.1524)
				)
			)
		)
		(duplicate_pad_numbers_are_jumpers no)
		(fp_line
			(start -0.508 -0.9398)
			(end -0.508 0.9398)
			(stroke
				(width 0.1524)
				(type default)
			)
			(layer "F.SilkS")
		)
		(fp_line
			(start 0.508 -0.9398)
			(end -0.508 -0.9398)
			(stroke
				(width 0.1524)
				(type default)
			)
			(layer "F.SilkS")
		)
		(fp_rect
			(start -0.508 0.9398)
			(end 0.508 -0.9398)
			(stroke
				(width 0)
				(type default)
			)
			(fill no)
			(layer "F.CrtYd")
		)
		(fp_rect
			(start -0.508 0.9398)
			(end 0.508 -0.9398)
			(stroke
				(width 0)
				(type default)
			)
			(fill no)
			(layer "F.Fab")
		)
		(pad "1" smd custom
			(at 0 -0.4445 270)
			(size 0.1397 0.1397)
			(layers "F.Cu" "F.Mask" "F.Paste")
			(net "P3V3_STBY_MODE")
			(options
				(clearance outline)
				(anchor circle)
			)
			(primitives
				(gr_poly
					(pts
						(arc
							(start -0.1778 -0.2794)
							(mid -0.249642 -0.249642)
							(end -0.2794 -0.1778)
						)
						(arc
							(start -0.2794 0.1778)
							(mid -0.249642 0.249642)
							(end -0.1778 0.2794)
						)
						(arc
							(start 0.1778 0.2794)
							(mid 0.249642 0.249642)
							(end 0.2794 0.1778)
						)
						(arc
							(start 0.2794 -0.1778)
							(mid 0.249642 -0.249642)
							(end 0.1778 -0.2794)
						)
					)
					(width 0)
					(fill yes)
				)
			)
		)
		(pad "2" smd custom
			(at 0 0.4445 270)
			(size 0.1397 0.1397)
			(layers "F.Cu" "F.Mask" "F.Paste")
			(net "PWRGD_P3V3_STBY")
			(options
				(clearance outline)
				(anchor circle)
			)
			(primitives
				(gr_poly
					(pts
						(arc
							(start -0.1778 -0.2794)
							(mid -0.249642 -0.249642)
							(end -0.2794 -0.1778)
						)
						(arc
							(start -0.2794 0.1778)
							(mid -0.249642 0.249642)
							(end -0.1778 0.2794)
						)
						(arc
							(start 0.1778 0.2794)
							(mid 0.249642 0.249642)
							(end 0.2794 0.1778)
						)
						(arc
							(start 0.2794 -0.1778)
							(mid 0.249642 -0.249642)
							(end 0.1778 -0.2794)
						)
					)
					(width 0)
					(fill yes)
				)
			)
		)
	)
	(footprint ""
		(layer "F.Cu")
		(at 158.7754 -127.5588)
		(property "Reference" "L10"
			(at 0 0 0)
			(layer "F.SilkS")
			(hide yes)
			(effects
				(font
					(size 1.27 1.27)
				)
			)
		)
		(property "Value" "COIL-3D3UH-48-GP"
			(at -3.8735 -3.048 0)
			(unlocked yes)
			(layer "F.Fab")
			(hide yes)
			(effects
				(font
					(size 1.016 1.016)
					(thickness 0.1524)
				)
			)
		)
		(property "Device Type" "L4947-1215H119"
			(at -3.8735 -4.572 0)
			(unlocked yes)
			(layer "F.Fab")
			(hide yes)
			(effects
				(font
					(size 1.016 1.016)
					(thickness 0.1524)
				)
			)
		)
		(duplicate_pad_numbers_are_jumpers no)
		(fp_line
			(start -2.6035 -3.429)
			(end 2.6035 -3.429)
			(stroke
				(width 0.1524)
				(type default)
			)
			(layer "F.SilkS")
		)
		(fp_line
			(start -2.6035 3.429)
			(end -2.6035 -3.429)
			(stroke
				(width 0.1524)
				(type default)
			)
			(layer "F.SilkS")
		)
		(fp_line
			(start 2.6035 -3.429)
			(end 2.6035 3.429)
			(stroke
				(width 0.1524)
				(type default)
			)
			(layer "F.SilkS")
		)
		(fp_line
			(start 2.6035 3.429)
			(end -2.6035 3.429)
			(stroke
				(width 0.1524)
				(type default)
			)
			(layer "F.SilkS")
		)
		(fp_rect
			(start -2.3495 2.4257)
			(end 2.3495 -2.4257)
			(stroke
				(width 0)
				(type default)
			)
			(fill no)
			(layer "F.CrtYd")
		)
		(fp_poly
			(pts
				(xy -2.8575 3.5052) (xy -2.8575 2.4257) (xy 2.3495 2.4257) (xy 2.3495 -2.4257) (xy -2.3495 -2.4257)
				(xy -2.3495 2.413) (xy -2.8575 2.413) (xy -2.8575 -3.5052) (xy 2.8575 -3.5052) (xy 2.8575 3.5052)
			)
			(stroke
				(width 0)
				(type default)
			)
			(fill no)
			(layer "F.CrtYd")
		)
		(fp_rect
			(start -2.8575 3.5052)
			(end 2.8575 -3.5052)
			(stroke
				(width 0)
				(type default)
			)
			(fill no)
			(layer "F.Fab")
		)
		(pad "1" smd rect
			(at 0 -1.999996)
			(size 2.0066 2.3622)
			(layers "F.Cu" "F.Mask" "F.Paste")
			(net "P1V8_STBY_SW")
		)
		(pad "2" smd rect
			(at 0 1.999996)
			(size 2.0066 2.3622)
			(layers "F.Cu" "F.Mask" "F.Paste")
			(net "P1V8_STBY")
		)
	)
)
